(kicad_pcb
	(version 20241229)
	(generator "pcbnew")
	(generator_version "9.0")
	(general
		(thickness 1.292)
		(legacy_teardrops no)
	)
	(paper "A4")
	(title_block
		(title "LPDDR5 Testbed")
		(date "2023-12-19")
		(rev "1.0.0")
		(comment 9 "footprints 133-138 of 160")
	)
	(layers
		(0 "F.Cu" signal)
		(4 "In1.Cu" power)
		(6 "In2.Cu" power)
		(8 "In3.Cu" signal)
		(10 "In4.Cu" signal)
		(2 "B.Cu" signal)
		(9 "F.Adhes" user "F.Adhesive")
		(11 "B.Adhes" user "B.Adhesive")
		(13 "F.Paste" user)
		(15 "B.Paste" user)
		(5 "F.SilkS" user "F.Silkscreen")
		(7 "B.SilkS" user "B.Silkscreen")
		(1 "F.Mask" user)
		(3 "B.Mask" user)
		(17 "Dwgs.User" user "User.Drawings")
		(19 "Cmts.User" user "User.Comments")
		(21 "Eco1.User" user "User.Eco1")
		(23 "Eco2.User" user "User.Eco2")
		(25 "Edge.Cuts" user)
		(27 "Margin" user)
		(31 "F.CrtYd" user "F.Courtyard")
		(29 "B.CrtYd" user "B.Courtyard")
		(35 "F.Fab" user)
		(33 "B.Fab" user)
	)
	(footprint "antmicro-footprints:C_0402_1005Metric"
		(layer "B.Cu")
		(at 129.175 73.75 180)
		(descr "Capacitor SMD 0402")
		(tags "capacitor SMD 0402")
		(property "Reference" "C38"
			(at 1.075 -0.35 0)
			(unlocked yes)
			(layer "B.SilkS")
			(effects
				(font
					(size 0.7 0.7)
					(thickness 0.15)
				)
				(justify left bottom mirror)
			)
		)
		(property "Value" "C_4u7_0402"
			(at -1.022927 -2.155213 0)
			(layer "B.Fab")
			(effects
				(font
					(size 0.7 0.7)
					(thickness 0.15)
				)
				(justify left bottom mirror)
			)
		)
		(property "Author" "Antmicro"
			(at 258.35 147.5 0)
			(layer "B.Fab")
			(hide yes)
			(effects
				(font
					(size 1 1)
					(thickness 0.15)
				)
				(justify mirror)
			)
		)
		(property "Dielectric" ""
			(at 258.35 147.5 0)
			(layer "B.Fab")
			(hide yes)
			(effects
				(font
					(size 1 1)
					(thickness 0.15)
				)
				(justify mirror)
			)
		)
		(property "License" "Apache-2.0"
			(at 258.35 147.5 0)
			(layer "B.Fab")
			(hide yes)
			(effects
				(font
					(size 1 1)
					(thickness 0.15)
				)
				(justify mirror)
			)
		)
		(property "MPN" "GRM155R61A475MEAAD"
			(at 258.35 147.5 0)
			(layer "B.Fab")
			(hide yes)
			(effects
				(font
					(size 1 1)
					(thickness 0.15)
				)
				(justify mirror)
			)
		)
		(property "Manufacturer" "Murata"
			(at 258.35 147.5 0)
			(layer "B.Fab")
			(hide yes)
			(effects
				(font
					(size 1 1)
					(thickness 0.15)
				)
				(justify mirror)
			)
		)
		(property "Val" "4u7"
			(at 258.35 147.5 0)
			(layer "B.Fab")
			(hide yes)
			(effects
				(font
					(size 1 1)
					(thickness 0.15)
				)
				(justify mirror)
			)
		)
		(property "Voltage" ""
			(at 258.35 147.5 0)
			(layer "B.Fab")
			(hide yes)
			(effects
				(font
					(size 1 1)
					(thickness 0.15)
				)
				(justify mirror)
			)
		)
		(sheetname "LPDDR5")
		(sheetfile "lpddr5.kicad_sch")
		(attr smd)
		(fp_rect
			(start -0.9659 0.481258)
			(end 0.9649 -0.458742)
			(stroke
				(width 0.05)
				(type solid)
			)
			(fill no)
			(layer "B.CrtYd")
		)
		(fp_line
			(start 0.499 0.25)
			(end 0.499 -0.248)
			(stroke
				(width 0.15)
				(type solid)
			)
			(layer "B.Fab")
		)
		(fp_line
			(start 0.499 -0.248)
			(end -0.499 -0.248)
			(stroke
				(width 0.15)
				(type solid)
			)
			(layer "B.Fab")
		)
		(fp_line
			(start -0.499 0.25)
			(end 0.499 0.25)
			(stroke
				(width 0.15)
				(type solid)
			)
			(layer "B.Fab")
		)
		(fp_line
			(start -0.499 -0.248)
			(end -0.499 0.25)
			(stroke
				(width 0.15)
				(type solid)
			)
			(layer "B.Fab")
		)
		(pad "1" smd roundrect
			(at -0.484 0 180)
			(size 0.59 0.64)
			(layers "B.Cu" "B.Mask" "B.Paste")
			(roundrect_rratio 0.25)
			(net 14 "GND")
			(pintype "passive")
		)
		(pad "2" smd roundrect
			(at 0.484 0 180)
			(size 0.59 0.64)
			(layers "B.Cu" "B.Mask" "B.Paste")
			(roundrect_rratio 0.25)
			(net 35 "+1V8")
			(pintype "passive")
		)
	)
	(footprint "antmicro-footprints:SOT-23-5"
		(layer "B.Cu")
		(at 107.25 82.9 -90)
		(property "Reference" "U7"
			(at 0.002 2 90)
			(unlocked yes)
			(layer "B.SilkS")
			(effects
				(font
					(size 0.7 0.7)
					(thickness 0.15)
				)
				(justify left bottom mirror)
			)
		)
		(property "Value" "AT24CS01_SOT23"
			(at 0.002 -2.799 90)
			(layer "B.Fab")
			(effects
				(font
					(size 0.7 0.7)
					(thickness 0.15)
				)
				(justify left bottom mirror)
			)
		)
		(property "Author" "Antmicro"
			(at 24.35 190.15 0)
			(layer "B.Fab")
			(hide yes)
			(effects
				(font
					(size 1 1)
					(thickness 0.15)
				)
				(justify mirror)
			)
		)
		(property "License" "Apache-2.0"
			(at 24.35 190.15 0)
			(layer "B.Fab")
			(hide yes)
			(effects
				(font
					(size 1 1)
					(thickness 0.15)
				)
				(justify mirror)
			)
		)
		(property "MPN" "AT24CS01-ST"
			(at 24.35 190.15 0)
			(layer "B.Fab")
			(hide yes)
			(effects
				(font
					(size 1 1)
					(thickness 0.15)
				)
				(justify mirror)
			)
		)
		(property "Manufacturer" "Atmel"
			(at 24.35 190.15 0)
			(layer "B.Fab")
			(hide yes)
			(effects
				(font
					(size 1 1)
					(thickness 0.15)
				)
				(justify mirror)
			)
		)
		(sheetname "SODIMM")
		(sheetfile "sodim.kicad_sch")
		(attr smd)
		(fp_line
			(start -0.8 1.6)
			(end -0.5 1.6)
			(stroke
				(width 0.15)
				(type solid)
			)
			(layer "B.SilkS")
		)
		(fp_line
			(start -0.8 1.6)
			(end -0.8 1.3)
			(stroke
				(width 0.15)
				(type solid)
			)
			(layer "B.SilkS")
		)
		(fp_line
			(start 0.8 1.6)
			(end 0.5 1.6)
			(stroke
				(width 0.15)
				(type solid)
			)
			(layer "B.SilkS")
		)
		(fp_line
			(start 0.8 1.3)
			(end 0.8 1.6)
			(stroke
				(width 0.15)
				(type solid)
			)
			(layer "B.SilkS")
		)
		(fp_line
			(start 0.8 -0.55)
			(end 0.8 0.55)
			(stroke
				(width 0.15)
				(type solid)
			)
			(layer "B.SilkS")
		)
		(fp_line
			(start 0.8 -1.3)
			(end 0.8 -1.599)
			(stroke
				(width 0.15)
				(type solid)
			)
			(layer "B.SilkS")
		)
		(fp_line
			(start 0.8 -1.599)
			(end 0.549 -1.599)
			(stroke
				(width 0.15)
				(type solid)
			)
			(layer "B.SilkS")
		)
		(fp_line
			(start -0.85 -1.6)
			(end -0.85 -1.301)
			(stroke
				(width 0.15)
				(type solid)
			)
			(layer "B.SilkS")
		)
		(fp_line
			(start -0.55 -1.6)
			(end -0.85 -1.6)
			(stroke
				(width 0.15)
				(type solid)
			)
			(layer "B.SilkS")
		)
		(fp_circle
			(center -1.25 1.5)
			(end -1.2 1.5)
			(stroke
				(width 0.15)
				(type solid)
			)
			(fill yes)
			(layer "B.SilkS")
		)
		(fp_rect
			(start 1.9 1.76)
			(end -1.9 -1.75)
			(stroke
				(width 0.05)
				(type solid)
			)
			(fill no)
			(layer "B.CrtYd")
		)
		(fp_line
			(start -0.398 1.526)
			(end -0.874 1.05)
			(stroke
				(width 0.15)
				(type solid)
			)
			(layer "B.Fab")
		)
		(fp_rect
			(start 0.874 -1.523)
			(end -0.873 1.525)
			(stroke
				(width 0.15)
				(type solid)
			)
			(fill no)
			(layer "B.Fab")
		)
		(pad "1" smd rect
			(at -1.351 0.951)
			(size 0.55 1)
			(layers "B.Cu" "B.Mask" "B.Paste")
			(net 18 "/SODIMM/HSCL")
			(pinfunction "SCL")
			(pintype "passive")
		)
		(pad "2" smd rect
			(at -1.351 0)
			(size 0.55 1)
			(layers "B.Cu" "B.Mask" "B.Paste")
			(net 14 "GND")
			(pinfunction "GND")
			(pintype "passive")
		)
		(pad "3" smd rect
			(at -1.351 -0.949)
			(size 0.55 1)
			(layers "B.Cu" "B.Mask" "B.Paste")
			(net 19 "/SODIMM/HSDA")
			(pinfunction "SDA")
			(pintype "passive")
		)
		(pad "4" smd rect
			(at 1.35 -0.949)
			(size 0.55 1)
			(layers "B.Cu" "B.Mask" "B.Paste")
			(net 35 "+1V8")
			(pinfunction "VCC")
			(pintype "passive")
		)
		(pad "5" smd rect
			(at 1.35 0.951)
			(size 0.55 1)
			(layers "B.Cu" "B.Mask" "B.Paste")
			(net 14 "GND")
			(pinfunction "WP")
			(pintype "passive")
		)
	)
	(footprint "antmicro-footprints:C_0402_1005Metric"
		(layer "B.Cu")
		(at 134.775 78 -90)
		(descr "Capacitor SMD 0402")
		(tags "capacitor SMD 0402")
		(property "Reference" "C68"
			(at -1.1 0.675 90)
			(unlocked yes)
			(layer "B.SilkS")
			(effects
				(font
					(size 0.7 0.7)
					(thickness 0.15)
				)
				(justify left bottom mirror)
			)
		)
		(property "Value" "C_4u7_0402"
			(at -1.022927 -2.155213 90)
			(layer "B.Fab")
			(effects
				(font
					(size 0.7 0.7)
					(thickness 0.15)
				)
				(justify left bottom mirror)
			)
		)
		(property "Author" "Antmicro"
			(at 56.775 212.775 0)
			(layer "B.Fab")
			(hide yes)
			(effects
				(font
					(size 1 1)
					(thickness 0.15)
				)
				(justify mirror)
			)
		)
		(property "Dielectric" ""
			(at 56.775 212.775 0)
			(layer "B.Fab")
			(hide yes)
			(effects
				(font
					(size 1 1)
					(thickness 0.15)
				)
				(justify mirror)
			)
		)
		(property "License" "Apache-2.0"
			(at 56.775 212.775 0)
			(layer "B.Fab")
			(hide yes)
			(effects
				(font
					(size 1 1)
					(thickness 0.15)
				)
				(justify mirror)
			)
		)
		(property "MPN" "GRM155R61A475MEAAD"
			(at 56.775 212.775 0)
			(layer "B.Fab")
			(hide yes)
			(effects
				(font
					(size 1 1)
					(thickness 0.15)
				)
				(justify mirror)
			)
		)
		(property "Manufacturer" "Murata"
			(at 56.775 212.775 0)
			(layer "B.Fab")
			(hide yes)
			(effects
				(font
					(size 1 1)
					(thickness 0.15)
				)
				(justify mirror)
			)
		)
		(property "Val" "4u7"
			(at 56.775 212.775 0)
			(layer "B.Fab")
			(hide yes)
			(effects
				(font
					(size 1 1)
					(thickness 0.15)
				)
				(justify mirror)
			)
		)
		(property "Voltage" ""
			(at 56.775 212.775 0)
			(layer "B.Fab")
			(hide yes)
			(effects
				(font
					(size 1 1)
					(thickness 0.15)
				)
				(justify mirror)
			)
		)
		(sheetname "LPDDR5")
		(sheetfile "lpddr5.kicad_sch")
		(attr smd)
		(fp_rect
			(start -0.9659 0.481258)
			(end 0.9649 -0.458742)
			(stroke
				(width 0.05)
				(type solid)
			)
			(fill no)
			(layer "B.CrtYd")
		)
		(fp_line
			(start -0.499 0.25)
			(end 0.499 0.25)
			(stroke
				(width 0.15)
				(type solid)
			)
			(layer "B.Fab")
		)
		(fp_line
			(start 0.499 0.25)
			(end 0.499 -0.248)
			(stroke
				(width 0.15)
				(type solid)
			)
			(layer "B.Fab")
		)
		(fp_line
			(start -0.499 -0.248)
			(end -0.499 0.25)
			(stroke
				(width 0.15)
				(type solid)
			)
			(layer "B.Fab")
		)
		(fp_line
			(start 0.499 -0.248)
			(end -0.499 -0.248)
			(stroke
				(width 0.15)
				(type solid)
			)
			(layer "B.Fab")
		)
		(pad "1" smd roundrect
			(at -0.484 0 270)
			(size 0.59 0.64)
			(layers "B.Cu" "B.Mask" "B.Paste")
			(roundrect_rratio 0.25)
			(net 14 "GND")
			(pintype "passive")
		)
		(pad "2" smd roundrect
			(at 0.484 0 270)
			(size 0.59 0.64)
			(layers "B.Cu" "B.Mask" "B.Paste")
			(roundrect_rratio 0.25)
			(net 13 "+1V05")
			(pintype "passive")
		)
	)
	(footprint "antmicro-footprints:C_0402_1005Metric"
		(layer "B.Cu")
		(at 140.375 74.95)
		(descr "Capacitor SMD 0402")
		(tags "capacitor SMD 0402")
		(property "Reference" "C49"
			(at 1.125 0.35 0)
			(unlocked yes)
			(layer "B.SilkS")
			(effects
				(font
					(size 0.7 0.7)
					(thickness 0.15)
				)
				(justify right bottom mirror)
			)
		)
		(property "Value" "C_4u7_0402"
			(at -1.022927 -2.155213 0)
			(layer "B.Fab")
			(effects
				(font
					(size 0.7 0.7)
					(thickness 0.15)
				)
				(justify right bottom mirror)
			)
		)
		(property "Author" "Antmicro"
			(at 0 0 0)
			(layer "B.Fab")
			(hide yes)
			(effects
				(font
					(size 1 1)
					(thickness 0.15)
				)
				(justify mirror)
			)
		)
		(property "Dielectric" ""
			(at 0 0 0)
			(layer "B.Fab")
			(hide yes)
			(effects
				(font
					(size 1 1)
					(thickness 0.15)
				)
				(justify mirror)
			)
		)
		(property "License" "Apache-2.0"
			(at 0 0 0)
			(layer "B.Fab")
			(hide yes)
			(effects
				(font
					(size 1 1)
					(thickness 0.15)
				)
				(justify mirror)
			)
		)
		(property "MPN" "GRM155R61A475MEAAD"
			(at 0 0 0)
			(layer "B.Fab")
			(hide yes)
			(effects
				(font
					(size 1 1)
					(thickness 0.15)
				)
				(justify mirror)
			)
		)
		(property "Manufacturer" "Murata"
			(at 0 0 0)
			(layer "B.Fab")
			(hide yes)
			(effects
				(font
					(size 1 1)
					(thickness 0.15)
				)
				(justify mirror)
			)
		)
		(property "Val" "4u7"
			(at 0 0 0)
			(layer "B.Fab")
			(hide yes)
			(effects
				(font
					(size 1 1)
					(thickness 0.15)
				)
				(justify mirror)
			)
		)
		(property "Voltage" ""
			(at 0 0 0)
			(layer "B.Fab")
			(hide yes)
			(effects
				(font
					(size 1 1)
					(thickness 0.15)
				)
				(justify mirror)
			)
		)
		(sheetname "LPDDR5")
		(sheetfile "lpddr5.kicad_sch")
		(attr smd)
		(fp_rect
			(start -0.9659 0.481258)
			(end 0.9649 -0.458742)
			(stroke
				(width 0.05)
				(type solid)
			)
			(fill no)
			(layer "B.CrtYd")
		)
		(fp_line
			(start -0.499 -0.248)
			(end -0.499 0.25)
			(stroke
				(width 0.15)
				(type solid)
			)
			(layer "B.Fab")
		)
		(fp_line
			(start -0.499 0.25)
			(end 0.499 0.25)
			(stroke
				(width 0.15)
				(type solid)
			)
			(layer "B.Fab")
		)
		(fp_line
			(start 0.499 -0.248)
			(end -0.499 -0.248)
			(stroke
				(width 0.15)
				(type solid)
			)
			(layer "B.Fab")
		)
		(fp_line
			(start 0.499 0.25)
			(end 0.499 -0.248)
			(stroke
				(width 0.15)
				(type solid)
			)
			(layer "B.Fab")
		)
		(pad "1" smd roundrect
			(at -0.484 0)
			(size 0.59 0.64)
			(layers "B.Cu" "B.Mask" "B.Paste")
			(roundrect_rratio 0.25)
			(net 14 "GND")
			(pintype "passive")
		)
		(pad "2" smd roundrect
			(at 0.484 0)
			(size 0.59 0.64)
			(layers "B.Cu" "B.Mask" "B.Paste")
			(roundrect_rratio 0.25)
			(net 4 "+0V5")
			(pintype "passive")
		)
	)
	(footprint "antmicro-footprints:R_0402_1005Metric"
		(layer "B.Cu")
		(at 117.13 90.94 90)
		(descr "Resistor SMD 0402")
		(tags "resistor SMD 0402")
		(property "Reference" "R11"
			(at -0.16 -2.73 0)
			(unlocked yes)
			(layer "B.SilkS")
			(effects
				(font
					(size 0.7 0.7)
					(thickness 0.15)
				)
				(justify right bottom mirror)
			)
		)
		(property "Value" "R_100R_0402"
			(at -1.011843 -1.772047 90)
			(layer "B.Fab")
			(effects
				(font
					(size 0.7 0.7)
					(thickness 0.15)
				)
				(justify right bottom mirror)
			)
		)
		(property "Author" "Antmicro"
			(at 208.07 -26.19 0)
			(layer "B.Fab")
			(hide yes)
			(effects
				(font
					(size 1 1)
					(thickness 0.15)
				)
				(justify mirror)
			)
		)
		(property "License" "Apache-2.0"
			(at 208.07 -26.19 0)
			(layer "B.Fab")
			(hide yes)
			(effects
				(font
					(size 1 1)
					(thickness 0.15)
				)
				(justify mirror)
			)
		)
		(property "MPN" "CR0402-FX-1000GLF"
			(at 208.07 -26.19 0)
			(layer "B.Fab")
			(hide yes)
			(effects
				(font
					(size 1 1)
					(thickness 0.15)
				)
				(justify mirror)
			)
		)
		(property "Manufacturer" "Bourns"
			(at 208.07 -26.19 0)
			(layer "B.Fab")
			(hide yes)
			(effects
				(font
					(size 1 1)
					(thickness 0.15)
				)
				(justify mirror)
			)
		)
		(property "Tolerance" "1%"
			(at 208.07 -26.19 0)
			(layer "B.Fab")
			(hide yes)
			(effects
				(font
					(size 1 1)
					(thickness 0.15)
				)
				(justify mirror)
			)
		)
		(property "Val" "100R"
			(at 208.07 -26.19 0)
			(layer "B.Fab")
			(hide yes)
			(effects
				(font
					(size 1 1)
					(thickness 0.15)
				)
				(justify mirror)
			)
		)
		(sheetname "Translators")
		(sheetfile "translators.kicad_sch")
		(attr smd)
		(fp_rect
			(start -0.93 0.47)
			(end 0.93 -0.47)
			(stroke
				(width 0.05)
				(type solid)
			)
			(fill no)
			(layer "B.CrtYd")
		)
		(fp_rect
			(start -0.5 0.25)
			(end 0.5 -0.25)
			(stroke
				(width 0.15)
				(type solid)
			)
			(fill no)
			(layer "B.Fab")
		)
		(pad "1" smd roundrect
			(at -0.485 0 90)
			(size 0.59 0.64)
			(layers "B.Cu" "B.Mask" "B.Paste")
			(roundrect_rratio 0.25)
			(net 171 "/SODIMM/LPDDR5_IN_A.WCK0_N")
			(pintype "passive")
		)
		(pad "2" smd roundrect
			(at 0.485 0 90)
			(size 0.59 0.64)
			(layers "B.Cu" "B.Mask" "B.Paste")
			(roundrect_rratio 0.25)
			(net 46 "/LPDDR5/LPDDR5_A.WCK0_N")
			(pintype "passive")
		)
	)
	(footprint "antmicro-footprints:C_0402_1005Metric"
		(layer "B.Cu")
		(at 127.1 79.15)
		(descr "Capacitor SMD 0402")
		(tags "capacitor SMD 0402")
		(property "Reference" "C53"
			(at -3.2 0.3 0)
			(unlocked yes)
			(layer "B.SilkS")
			(effects
				(font
					(size 0.7 0.7)
					(thickness 0.15)
				)
				(justify right bottom mirror)
			)
		)
		(property "Value" "C_4u7_0402"
			(at -1.022927 -2.155213 0)
			(layer "B.Fab")
			(effects
				(font
					(size 0.7 0.7)
					(thickness 0.15)
				)
				(justify right bottom mirror)
			)
		)
		(property "Author" "Antmicro"
			(at 0 0 0)
			(layer "B.Fab")
			(hide yes)
			(effects
				(font
					(size 1 1)
					(thickness 0.15)
				)
				(justify mirror)
			)
		)
		(property "Dielectric" ""
			(at 0 0 0)
			(layer "B.Fab")
			(hide yes)
			(effects
				(font
					(size 1 1)
					(thickness 0.15)
				)
				(justify mirror)
			)
		)
		(property "License" "Apache-2.0"
			(at 0 0 0)
			(layer "B.Fab")
			(hide yes)
			(effects
				(font
					(size 1 1)
					(thickness 0.15)
				)
				(justify mirror)
			)
		)
		(property "MPN" "GRM155R61A475MEAAD"
			(at 0 0 0)
			(layer "B.Fab")
			(hide yes)
			(effects
				(font
					(size 1 1)
					(thickness 0.15)
				)
				(justify mirror)
			)
		)
		(property "Manufacturer" "Murata"
			(at 0 0 0)
			(layer "B.Fab")
			(hide yes)
			(effects
				(font
					(size 1 1)
					(thickness 0.15)
				)
				(justify mirror)
			)
		)
		(property "Val" "4u7"
			(at 0 0 0)
			(layer "B.Fab")
			(hide yes)
			(effects
				(font
					(size 1 1)
					(thickness 0.15)
				)
				(justify mirror)
			)
		)
		(property "Voltage" ""
			(at 0 0 0)
			(layer "B.Fab")
			(hide yes)
			(effects
				(font
					(size 1 1)
					(thickness 0.15)
				)
				(justify mirror)
			)
		)
		(sheetname "LPDDR5")
		(sheetfile "lpddr5.kicad_sch")
		(attr smd)
		(fp_rect
			(start -0.9659 0.481258)
			(end 0.9649 -0.458742)
			(stroke
				(width 0.05)
				(type solid)
			)
			(fill no)
			(layer "B.CrtYd")
		)
		(fp_line
			(start -0.499 -0.248)
			(end -0.499 0.25)
			(stroke
				(width 0.15)
				(type solid)
			)
			(layer "B.Fab")
		)
		(fp_line
			(start -0.499 0.25)
			(end 0.499 0.25)
			(stroke
				(width 0.15)
				(type solid)
			)
			(layer "B.Fab")
		)
		(fp_line
			(start 0.499 -0.248)
			(end -0.499 -0.248)
			(stroke
				(width 0.15)
				(type solid)
			)
			(layer "B.Fab")
		)
		(fp_line
			(start 0.499 0.25)
			(end 0.499 -0.248)
			(stroke
				(width 0.15)
				(type solid)
			)
			(layer "B.Fab")
		)
		(pad "1" smd roundrect
			(at -0.484 0)
			(size 0.59 0.64)
			(layers "B.Cu" "B.Mask" "B.Paste")
			(roundrect_rratio 0.25)
			(net 14 "GND")
			(pintype "passive")
		)
		(pad "2" smd roundrect
			(at 0.484 0)
			(size 0.59 0.64)
			(layers "B.Cu" "B.Mask" "B.Paste")
			(roundrect_rratio 0.25)
			(net 13 "+1V05")
			(pintype "passive")
		)
	)
)
